# S9S_MB_2U (Grand Teton) — schematic netlist excerpt (pin names and nets, part order shuffled) for the footprints in the layout excerpt that follows; sources: Cadence DE-HDL packaged netlist, KiCad conversion of 03242023_DA0F0TMBIJ0_F0T_Motherboard_J_brd_V01_OCP.brd

J90  SCONN56_123276793  SCONN56_1-2327679-3 IO  pkg CON_F56S2H4D_P0-6W4-6_LUHXA  page 191
  GND_A1  = GND
  GND_A2  = GND
  GND_A3  = GND
  GND_A4  = GND
  GND_A5  = GND
  GND_A6  = GND
  SMBCLK  = SMB_E1S_3V3AUX_ISO_SCL
  SMBDAT  = SMB_E1S_3V3AUX_ISO_SDA
  \smbrst#\  = RST_SMB_E1S_0_N
  \led#_activity\  = E1S_0_LED_ACT_N
  \perst1#_clkreq#\  = E1S_0_PERST1_CLKREQ_N
  \prsnt0#\  = E1S_0_PRSNT_N
  GND_A13  = GND
  REFCLK_N1  = TP_CLK_100M_E1S_0_DN
  REFCLK_P1  = TP_CLK_100M_E1S_0_DP
  GND_A16  = GND
  PER_N0  = P3E_PCH_E1S_RX_DP<0>
  PER_P0  = P3E_PCH_E1S_RX_DN<0>
  GND_A19  = GND
  PER_N1  = P3E_PCH_E1S_RX_DN<1>
  PER_P1  = P3E_PCH_E1S_RX_DP<1>
  GND_A22  = GND
  PER_N2  = P3E_PCH_E1S_RX_DN<2>
  PER_P2  = P3E_PCH_E1S_RX_DP<2>
  GND_A25  = GND
  PER_N3  = P3E_PCH_E1S_RX_DN<3>
  PER_P3  = P3E_PCH_E1S_RX_DP<3>
  GND_A28  = GND
  P12V_B1  = P12V_E1S_0
  P12V_B2  = P12V_E1S_0
  P12V_B3  = P12V_E1S_0
  P12V_B4  = P12V_E1S_0
  P12V_B5  = P12V_E1S_0
  P12V_B6  = P12V_E1S_0
  MFG  = TP_E1S_0_MFG
  RFU  = TP_E1S_0_RFU
  \dualporten#\  = PU_E1S_0_DUALPORT_EN_N
  \perst0#\  = RST_PCIE_PCH_E1S_PERST_N
  P3V3_AUX  = P3V3_E1S_0
  PWRDIS  = E1S_0_PWRDIS
  GND_B13  = GND
  REFCLK_N0  = CLK_100M_E1S_0_DN
  REFCLK_P0  = CLK_100M_E1S_0_DP
  GND_B16  = GND
  PET_N0  = P3E_PCH_E1S_TX_C_DP<0>
  PET_P0  = P3E_PCH_E1S_TX_C_DN<0>
  GND_B19  = GND
  PET_N1  = P3E_PCH_E1S_TX_C_DP<1>
  PET_P1  = P3E_PCH_E1S_TX_C_DN<1>
  GND_B22  = GND
  PET_N2  = P3E_PCH_E1S_TX_C_DN<2>
  PET_P2  = P3E_PCH_E1S_TX_C_DP<2>
  GND_B25  = GND
  PET_N3  = P3E_PCH_E1S_TX_C_DN<3>
  PET_P3  = P3E_PCH_E1S_TX_C_DP<3>
  GND_B28  = GND
  G1  = GND
  G2  = GND

(kicad_pcb
	(version 20260206)
	(generator "pcbnew")
	(generator_version "10.0")
	(general
		(thickness 1.6)
		(legacy_teardrops no)
	)
	(paper "A4")
	(title_block
		(title "03242023_DA0F0TMBIJ0_F0T_Motherboard_J_brd_V01_OCP.brd")
		(comment 1 "Grand Teton / footprint 2802 of 6105 (J90), pads 1-46 of 60")
	)
	(layers
		(0 "F.Cu" signal "TOP")
		(4 "In1.Cu" signal "GND")
		(6 "In2.Cu" signal "IN1")
		(8 "In3.Cu" signal "GND1")
		(10 "In4.Cu" signal "IN2")
		(12 "In5.Cu" signal "GND2")
		(14 "In6.Cu" signal "IN3")
		(16 "In7.Cu" signal "GND3")
		(18 "In8.Cu" signal "VCC")
		(20 "In9.Cu" signal "VCC1")
		(22 "In10.Cu" signal "GND4")
		(24 "In11.Cu" signal "IN4")
		(26 "In12.Cu" signal "GND5")
		(28 "In13.Cu" signal "IN5")
		(30 "In14.Cu" signal "GND6")
		(32 "In15.Cu" signal "IN6")
		(34 "In16.Cu" signal "GND7")
		(2 "B.Cu" signal "BOTTOM")
		(9 "F.Adhes" user "F.Adhesive")
		(11 "B.Adhes" user "B.Adhesive")
		(13 "F.Paste" user "Package Geometry/Pastemask Top")
		(15 "B.Paste" user "Package Geometry/Pastemask Bottom")
		(5 "F.SilkS" user "Ref Des/Silkscreen Top")
		(7 "B.SilkS" user "Ref Des/Silkscreen Bottom")
		(1 "F.Mask" user "Board Geometry/Soldermask Top")
		(3 "B.Mask" user "Board Geometry/Soldermask Bottom")
		(17 "Dwgs.User" user "User.Drawings")
		(19 "Cmts.User" user "User.Comments")
		(21 "Eco1.User" user "User.Eco1")
		(23 "Eco2.User" user "User.Eco2")
		(25 "Edge.Cuts" user "Board Geometry/Outline")
		(27 "Margin" user)
		(31 "F.CrtYd" user "Package Geometry/Place Bound Top")
		(29 "B.CrtYd" user "Package Geometry/Place Bound Bottom")
		(35 "F.Fab" user "Ref Des/Assembly Top")
		(33 "B.Fab" user "Ref Des/Assembly Bottom")
	)
	(footprint ""
		(layer "F.Cu")
		(at 234.300014 -50.55997 180)
		(property "Reference" "J90"
			(at -0.596646 16.126968 0)
			(unlocked yes)
			(layer "F.SilkS")
			(effects
				(font
					(size 0.7874 0.5842)
					(thickness 0.1524)
				)
			)
		)
		(property "Value" ""
			(at 0 0 180)
			(layer "F.Fab")
			(effects
				(font
					(size 1.27 1.27)
				)
			)
		)
		(duplicate_pad_numbers_are_jumpers no)
		(pad "" np_thru_hole circle
			(at -1.75006 -9.815068 90)
			(size 1.1176 1.1176)
			(drill 1.1176)
			(layers "*.Cu" "*.Mask")
			(clearance 0.381)
			(thermal_gap 0.381)
		)
		(pad "" np_thru_hole circle
			(at 0 9.815068 90)
			(size 1.1176 1.1176)
			(drill 1.1176)
			(layers "*.Cu" "*.Mask")
			(clearance 0.381)
			(thermal_gap 0.381)
		)
		(pad "A1" smd rect
			(at 2.29997 -7.994904 90)
			(size 0.381 1.27)
			(layers "F.Cu" "F.Mask" "F.Paste")
			(net "GND")
		)
		(pad "A2" smd rect
			(at 2.29997 -7.394956 90)
			(size 0.381 1.27)
			(layers "F.Cu" "F.Mask" "F.Paste")
			(net "GND")
		)
		(pad "A3" smd rect
			(at 2.29997 -6.795008 90)
			(size 0.381 1.27)
			(layers "F.Cu" "F.Mask" "F.Paste")
			(net "GND")
		)
		(pad "A4" smd rect
			(at 2.29997 -6.19506 90)
			(size 0.381 1.27)
			(layers "F.Cu" "F.Mask" "F.Paste")
			(net "GND")
		)
		(pad "A5" smd rect
			(at 2.29997 -5.595112 90)
			(size 0.381 1.27)
			(layers "F.Cu" "F.Mask" "F.Paste")
			(net "GND")
		)
		(pad "A6" smd rect
			(at 2.29997 -4.99491 90)
			(size 0.381 1.27)
			(layers "F.Cu" "F.Mask" "F.Paste")
			(net "GND")
		)
		(pad "A7" smd rect
			(at 2.29997 -4.394962 90)
			(size 0.381 1.27)
			(layers "F.Cu" "F.Mask" "F.Paste")
			(net "SMB_E1S_3V3AUX_ISO_SCL")
		)
		(pad "A8" smd rect
			(at 2.29997 -3.795014 90)
			(size 0.381 1.27)
			(layers "F.Cu" "F.Mask" "F.Paste")
			(net "SMB_E1S_3V3AUX_ISO_SDA")
		)
		(pad "A9" smd rect
			(at 2.29997 -3.195066 90)
			(size 0.381 1.27)
			(layers "F.Cu" "F.Mask" "F.Paste")
			(net "RST_SMB_E1S_0_N")
		)
		(pad "A10" smd rect
			(at 2.29997 -2.595118 90)
			(size 0.381 1.27)
			(layers "F.Cu" "F.Mask" "F.Paste")
			(net "E1S_0_LED_ACT_N")
		)
		(pad "A11" smd rect
			(at 2.29997 -1.994916 90)
			(size 0.381 1.27)
			(layers "F.Cu" "F.Mask" "F.Paste")
			(net "E1S_0_PERST1_CLKREQ_N")
		)
		(pad "A12" smd rect
			(at 2.29997 -1.394968 90)
			(size 0.381 1.27)
			(layers "F.Cu" "F.Mask" "F.Paste")
			(net "E1S_0_PRSNT_N")
		)
		(pad "A13" smd rect
			(at 2.29997 -0.79502 90)
			(size 0.381 1.27)
			(layers "F.Cu" "F.Mask" "F.Paste")
			(net "GND")
		)
		(pad "A14" smd rect
			(at 2.29997 -0.195072 90)
			(size 0.381 1.27)
			(layers "F.Cu" "F.Mask" "F.Paste")
			(net "TP_CLK_100M_E1S_0_DN")
		)
		(pad "A15" smd rect
			(at 2.29997 0.404876 90)
			(size 0.381 1.27)
			(layers "F.Cu" "F.Mask" "F.Paste")
			(net "TP_CLK_100M_E1S_0_DP")
		)
		(pad "A16" smd rect
			(at 2.29997 1.005078 90)
			(size 0.381 1.27)
			(layers "F.Cu" "F.Mask" "F.Paste")
			(net "GND")
		)
		(pad "A17" smd rect
			(at 2.29997 1.605026 90)
			(size 0.381 1.27)
			(layers "F.Cu" "F.Mask" "F.Paste")
			(net "P3E_PCH_E1S_RX_DP<0>")
		)
		(pad "A18" smd rect
			(at 2.29997 2.204974 90)
			(size 0.381 1.27)
			(layers "F.Cu" "F.Mask" "F.Paste")
			(net "P3E_PCH_E1S_RX_DN<0>")
		)
		(pad "A19" smd rect
			(at 2.29997 2.804922 90)
			(size 0.381 1.27)
			(layers "F.Cu" "F.Mask" "F.Paste")
			(net "GND")
		)
		(pad "A20" smd rect
			(at 2.29997 3.405124 90)
			(size 0.381 1.27)
			(layers "F.Cu" "F.Mask" "F.Paste")
			(net "P3E_PCH_E1S_RX_DN<1>")
		)
		(pad "A21" smd rect
			(at 2.29997 4.005072 90)
			(size 0.381 1.27)
			(layers "F.Cu" "F.Mask" "F.Paste")
			(net "P3E_PCH_E1S_RX_DP<1>")
		)
		(pad "A22" smd rect
			(at 2.29997 4.60502 90)
			(size 0.381 1.27)
			(layers "F.Cu" "F.Mask" "F.Paste")
			(net "GND")
		)
		(pad "A23" smd rect
			(at 2.29997 5.204968 90)
			(size 0.381 1.27)
			(layers "F.Cu" "F.Mask" "F.Paste")
			(net "P3E_PCH_E1S_RX_DN<2>")
		)
		(pad "A24" smd rect
			(at 2.29997 5.804916 90)
			(size 0.381 1.27)
			(layers "F.Cu" "F.Mask" "F.Paste")
			(net "P3E_PCH_E1S_RX_DP<2>")
		)
		(pad "A25" smd rect
			(at 2.29997 6.405118 90)
			(size 0.381 1.27)
			(layers "F.Cu" "F.Mask" "F.Paste")
			(net "GND")
		)
		(pad "A26" smd rect
			(at 2.29997 7.005066 90)
			(size 0.381 1.27)
			(layers "F.Cu" "F.Mask" "F.Paste")
			(net "P3E_PCH_E1S_RX_DN<3>")
		)
		(pad "A27" smd rect
			(at 2.29997 7.605014 90)
			(size 0.381 1.27)
			(layers "F.Cu" "F.Mask" "F.Paste")
			(net "P3E_PCH_E1S_RX_DP<3>")
		)
		(pad "A28" smd rect
			(at 2.29997 8.204962 90)
			(size 0.381 1.27)
			(layers "F.Cu" "F.Mask" "F.Paste")
			(net "GND")
		)
		(pad "B1" smd rect
			(at -2.29997 -7.994904 90)
			(size 0.381 1.27)
			(layers "F.Cu" "F.Mask" "F.Paste")
			(net "P12V_E1S_0")
		)
		(pad "B2" smd rect
			(at -2.29997 -7.394956 90)
			(size 0.381 1.27)
			(layers "F.Cu" "F.Mask" "F.Paste")
			(net "P12V_E1S_0")
		)
		(pad "B3" smd rect
			(at -2.29997 -6.795008 90)
			(size 0.381 1.27)
			(layers "F.Cu" "F.Mask" "F.Paste")
			(net "P12V_E1S_0")
		)
		(pad "B4" smd rect
			(at -2.29997 -6.19506 90)
			(size 0.381 1.27)
			(layers "F.Cu" "F.Mask" "F.Paste")
			(net "P12V_E1S_0")
		)
		(pad "B5" smd rect
			(at -2.29997 -5.595112 90)
			(size 0.381 1.27)
			(layers "F.Cu" "F.Mask" "F.Paste")
			(net "P12V_E1S_0")
		)
		(pad "B6" smd rect
			(at -2.29997 -4.99491 90)
			(size 0.381 1.27)
			(layers "F.Cu" "F.Mask" "F.Paste")
			(net "P12V_E1S_0")
		)
		(pad "B7" smd rect
			(at -2.29997 -4.394962 90)
			(size 0.381 1.27)
			(layers "F.Cu" "F.Mask" "F.Paste")
			(net "TP_E1S_0_MFG")
		)
		(pad "B8" smd rect
			(at -2.29997 -3.795014 90)
			(size 0.381 1.27)
			(layers "F.Cu" "F.Mask" "F.Paste")
			(net "TP_E1S_0_RFU")
		)
		(pad "B9" smd rect
			(at -2.29997 -3.195066 90)
			(size 0.381 1.27)
			(layers "F.Cu" "F.Mask" "F.Paste")
			(net "PU_E1S_0_DUALPORT_EN_N")
		)
		(pad "B10" smd rect
			(at -2.29997 -2.595118 90)
			(size 0.381 1.27)
			(layers "F.Cu" "F.Mask" "F.Paste")
			(net "RST_PCIE_PCH_E1S_PERST_N")
		)
		(pad "B11" smd rect
			(at -2.29997 -1.994916 90)
			(size 0.381 1.27)
			(layers "F.Cu" "F.Mask" "F.Paste")
			(net "P3V3_E1S_0")
		)
		(pad "B12" smd rect
			(at -2.29997 -1.394968 90)
			(size 0.381 1.27)
			(layers "F.Cu" "F.Mask" "F.Paste")
			(net "E1S_0_PWRDIS")
		)
		(pad "B13" smd rect
			(at -2.29997 -0.79502 90)
			(size 0.381 1.27)
			(layers "F.Cu" "F.Mask" "F.Paste")
			(net "GND")
		)
		(pad "B14" smd rect
			(at -2.29997 -0.195072 90)
			(size 0.381 1.27)
			(layers "F.Cu" "F.Mask" "F.Paste")
			(net "CLK_100M_E1S_0_DN")
		)
		(pad "B15" smd rect
			(at -2.29997 0.404876 90)
			(size 0.381 1.27)
			(layers "F.Cu" "F.Mask" "F.Paste")
			(net "CLK_100M_E1S_0_DP")
		)
		(pad "B16" smd rect
			(at -2.29997 1.005078 90)
			(size 0.381 1.27)
			(layers "F.Cu" "F.Mask" "F.Paste")
			(net "GND")
		)
	)
)
